FILE_TYPE = CONNECTIVITY;
{Allegro Design Entry HDL 17.2-2016 S081 (4005846) 1/11/2022}
"PAGE_NUMBER" = 130;
0"NC";
END.
